(kicad_pcb
	(version 20260206)
	(generator "pcbnew")
	(generator_version "10.0")
	(general
		(thickness 1.6)
		(legacy_teardrops no)
	)
	(paper "A4")
	(title_block
		(title "04192023_DAF0TMB3IC0_F0TG_MB_C_brd_V02_OCP.brd")
		(comment 1 "Grand Teton / footprints 510-516 of 8354")
	)
	(layers
		(0 "F.Cu" signal "TOP")
		(4 "In1.Cu" signal "GND")
		(6 "In2.Cu" signal "IN1")
		(8 "In3.Cu" signal "GND1")
		(10 "In4.Cu" signal "IN2")
		(12 "In5.Cu" signal "GND2")
		(14 "In6.Cu" signal "IN3")
		(16 "In7.Cu" signal "GND3")
		(18 "In8.Cu" signal "VCC")
		(20 "In9.Cu" signal "VCC1")
		(22 "In10.Cu" signal "GND4")
		(24 "In11.Cu" signal "IN4")
		(26 "In12.Cu" signal "GND5")
		(28 "In13.Cu" signal "IN5")
		(30 "In14.Cu" signal "GND6")
		(32 "In15.Cu" signal "IN6")
		(34 "In16.Cu" signal "GND7")
		(2 "B.Cu" signal "BOTTOM")
		(9 "F.Adhes" user "F.Adhesive")
		(11 "B.Adhes" user "B.Adhesive")
		(13 "F.Paste" user "Package Geometry/Pastemask Top")
		(15 "B.Paste" user "Package Geometry/Pastemask Bottom")
		(5 "F.SilkS" user "Ref Des/Silkscreen Top")
		(7 "B.SilkS" user "Ref Des/Silkscreen Bottom")
		(1 "F.Mask" user "Board Geometry/Soldermask Top")
		(3 "B.Mask" user "Board Geometry/Soldermask Bottom")
		(17 "Dwgs.User" user "User.Drawings")
		(19 "Cmts.User" user "User.Comments")
		(21 "Eco1.User" user "User.Eco1")
		(23 "Eco2.User" user "User.Eco2")
		(25 "Edge.Cuts" user "Board Geometry/Outline")
		(27 "Margin" user)
		(31 "F.CrtYd" user "Package Geometry/Place Bound Top")
		(29 "B.CrtYd" user "Package Geometry/Place Bound Bottom")
		(35 "F.Fab" user "Ref Des/Assembly Top")
		(33 "B.Fab" user "Ref Des/Assembly Bottom")
	)
	(footprint ""
		(layer "F.Cu")
		(at 364.139226 -62.0903)
		(property "Reference" "R8022"
			(at 0 0 0)
			(layer "F.SilkS")
			(hide yes)
			(effects
				(font
					(size 1.27 1.27)
				)
			)
		)
		(property "Value" ""
			(at 0 0 0)
			(layer "F.Fab")
			(effects
				(font
					(size 1.27 1.27)
				)
			)
		)
		(duplicate_pad_numbers_are_jumpers no)
		(fp_line
			(start -0.7874 -0.4064)
			(end 0.7874 -0.4064)
			(stroke
				(width 0.1524)
				(type default)
			)
			(layer "F.SilkS")
		)
		(fp_line
			(start -0.7874 0.4064)
			(end -0.7874 -0.4064)
			(stroke
				(width 0.1524)
				(type default)
			)
			(layer "F.SilkS")
		)
		(fp_line
			(start 0.7874 -0.4064)
			(end 0.7874 0.4064)
			(stroke
				(width 0.1524)
				(type default)
			)
			(layer "F.SilkS")
		)
		(fp_line
			(start 0.7874 0.4064)
			(end -0.7874 0.4064)
			(stroke
				(width 0.1524)
				(type default)
			)
			(layer "F.SilkS")
		)
		(fp_line
			(start -0.67945 -0.305054)
			(end -0.12065 -0.305054)
			(stroke
				(width 0.1)
				(type default)
			)
			(layer "F.Fab")
		)
		(fp_line
			(start -0.67945 0.3048)
			(end -0.67945 -0.305054)
			(stroke
				(width 0.1)
				(type default)
			)
			(layer "F.Fab")
		)
		(fp_line
			(start -0.12065 -0.305054)
			(end -0.12065 -0.2794)
			(stroke
				(width 0.1)
				(type default)
			)
			(layer "F.Fab")
		)
		(fp_line
			(start -0.12065 -0.2794)
			(end 0.12065 -0.2794)
			(stroke
				(width 0.1)
				(type default)
			)
			(layer "F.Fab")
		)
		(fp_line
			(start -0.12065 0.2794)
			(end -0.12065 0.3048)
			(stroke
				(width 0.1)
				(type default)
			)
			(layer "F.Fab")
		)
		(fp_line
			(start -0.12065 0.3048)
			(end -0.67945 0.3048)
			(stroke
				(width 0.1)
				(type default)
			)
			(layer "F.Fab")
		)
		(fp_line
			(start 0.120396 0.2794)
			(end -0.12065 0.2794)
			(stroke
				(width 0.1)
				(type default)
			)
			(layer "F.Fab")
		)
		(fp_line
			(start 0.120396 0.3048)
			(end 0.120396 0.2794)
			(stroke
				(width 0.1)
				(type default)
			)
			(layer "F.Fab")
		)
		(fp_line
			(start 0.12065 -0.3048)
			(end 0.67945 -0.3048)
			(stroke
				(width 0.1)
				(type default)
			)
			(layer "F.Fab")
		)
		(fp_line
			(start 0.12065 -0.2794)
			(end 0.12065 -0.3048)
			(stroke
				(width 0.1)
				(type default)
			)
			(layer "F.Fab")
		)
		(fp_line
			(start 0.67945 -0.3048)
			(end 0.67945 0.3048)
			(stroke
				(width 0.1)
				(type default)
			)
			(layer "F.Fab")
		)
		(fp_line
			(start 0.67945 0.3048)
			(end 0.120396 0.3048)
			(stroke
				(width 0.1)
				(type default)
			)
			(layer "F.Fab")
		)
		(pad "1" smd circle
			(at -0.40005 0)
			(size 0 0)
			(layers "F.Cu" "F.Mask" "F.Paste")
			(net "LED_P12V_AUX_R1")
		)
		(pad "2" smd circle
			(at 0.40005 0)
			(size 0 0)
			(layers "F.Cu" "F.Mask" "F.Paste")
			(net "LED_P12V_AUX_R2")
		)
	)
	(footprint ""
		(layer "F.Cu")
		(at 287.996884 -370.318792 -90)
		(property "Reference" "R6086"
			(at 0 0 270)
			(layer "F.SilkS")
			(hide yes)
			(effects
				(font
					(size 1.27 1.27)
				)
			)
		)
		(property "Value" ""
			(at 0 0 270)
			(layer "F.Fab")
			(effects
				(font
					(size 1.27 1.27)
				)
			)
		)
		(duplicate_pad_numbers_are_jumpers no)
		(fp_line
			(start -0.7874 0.4064)
			(end -0.7874 -0.4064)
			(stroke
				(width 0.1524)
				(type default)
			)
			(layer "F.SilkS")
		)
		(fp_line
			(start 0.7874 0.4064)
			(end -0.7874 0.4064)
			(stroke
				(width 0.1524)
				(type default)
			)
			(layer "F.SilkS")
		)
		(fp_line
			(start -0.7874 -0.4064)
			(end 0.7874 -0.4064)
			(stroke
				(width 0.1524)
				(type default)
			)
			(layer "F.SilkS")
		)
		(fp_line
			(start 0.7874 -0.4064)
			(end 0.7874 0.4064)
			(stroke
				(width 0.1524)
				(type default)
			)
			(layer "F.SilkS")
		)
		(fp_line
			(start -0.67945 0.3048)
			(end -0.67945 -0.305054)
			(stroke
				(width 0.1)
				(type default)
			)
			(layer "F.Fab")
		)
		(fp_line
			(start -0.12065 0.3048)
			(end -0.67945 0.3048)
			(stroke
				(width 0.1)
				(type default)
			)
			(layer "F.Fab")
		)
		(fp_line
			(start 0.120396 0.3048)
			(end 0.120396 0.2794)
			(stroke
				(width 0.1)
				(type default)
			)
			(layer "F.Fab")
		)
		(fp_line
			(start 0.67945 0.3048)
			(end 0.120396 0.3048)
			(stroke
				(width 0.1)
				(type default)
			)
			(layer "F.Fab")
		)
		(fp_line
			(start -0.12065 0.2794)
			(end -0.12065 0.3048)
			(stroke
				(width 0.1)
				(type default)
			)
			(layer "F.Fab")
		)
		(fp_line
			(start 0.120396 0.2794)
			(end -0.12065 0.2794)
			(stroke
				(width 0.1)
				(type default)
			)
			(layer "F.Fab")
		)
		(fp_line
			(start -0.12065 -0.2794)
			(end 0.12065 -0.2794)
			(stroke
				(width 0.1)
				(type default)
			)
			(layer "F.Fab")
		)
		(fp_line
			(start 0.12065 -0.2794)
			(end 0.12065 -0.3048)
			(stroke
				(width 0.1)
				(type default)
			)
			(layer "F.Fab")
		)
		(fp_line
			(start 0.12065 -0.3048)
			(end 0.67945 -0.3048)
			(stroke
				(width 0.1)
				(type default)
			)
			(layer "F.Fab")
		)
		(fp_line
			(start 0.67945 -0.3048)
			(end 0.67945 0.3048)
			(stroke
				(width 0.1)
				(type default)
			)
			(layer "F.Fab")
		)
		(fp_line
			(start -0.67945 -0.305054)
			(end -0.12065 -0.305054)
			(stroke
				(width 0.1)
				(type default)
			)
			(layer "F.Fab")
		)
		(fp_line
			(start -0.12065 -0.305054)
			(end -0.12065 -0.2794)
			(stroke
				(width 0.1)
				(type default)
			)
			(layer "F.Fab")
		)
		(pad "1" smd circle
			(at -0.40005 0 270)
			(size 0 0)
			(layers "F.Cu" "F.Mask" "F.Paste")
			(net "PVDDIO_P0_EN_R")
		)
		(pad "2" smd circle
			(at 0.40005 0 270)
			(size 0 0)
			(layers "F.Cu" "F.Mask" "F.Paste")
			(net "GND")
		)
	)
	(footprint ""
		(layer "F.Cu")
		(at 163.465002 -352.652838 90)
		(property "Reference" "PC96"
			(at 0 0 90)
			(layer "F.SilkS")
			(hide yes)
			(effects
				(font
					(size 1.27 1.27)
				)
			)
		)
		(property "Value" ""
			(at 0 0 90)
			(layer "F.Fab")
			(effects
				(font
					(size 1.27 1.27)
				)
			)
		)
		(duplicate_pad_numbers_are_jumpers no)
		(fp_line
			(start 0.7874 -0.4064)
			(end 0.7874 0.4064)
			(stroke
				(width 0.1524)
				(type default)
			)
			(layer "F.SilkS")
		)
		(fp_line
			(start -0.7874 -0.4064)
			(end 0.7874 -0.4064)
			(stroke
				(width 0.1524)
				(type default)
			)
			(layer "F.SilkS")
		)
		(fp_line
			(start 0.7874 0.4064)
			(end -0.7874 0.4064)
			(stroke
				(width 0.1524)
				(type default)
			)
			(layer "F.SilkS")
		)
		(fp_line
			(start -0.7874 0.4064)
			(end -0.7874 -0.4064)
			(stroke
				(width 0.1524)
				(type default)
			)
			(layer "F.SilkS")
		)
		(fp_line
			(start -0.12065 -0.305054)
			(end -0.12065 -0.2794)
			(stroke
				(width 0.1)
				(type default)
			)
			(layer "F.Fab")
		)
		(fp_line
			(start -0.67945 -0.305054)
			(end -0.12065 -0.305054)
			(stroke
				(width 0.1)
				(type default)
			)
			(layer "F.Fab")
		)
		(fp_line
			(start 0.67945 -0.3048)
			(end 0.67945 0.3048)
			(stroke
				(width 0.1)
				(type default)
			)
			(layer "F.Fab")
		)
		(fp_line
			(start 0.12065 -0.3048)
			(end 0.67945 -0.3048)
			(stroke
				(width 0.1)
				(type default)
			)
			(layer "F.Fab")
		)
		(fp_line
			(start 0.12065 -0.2794)
			(end 0.12065 -0.3048)
			(stroke
				(width 0.1)
				(type default)
			)
			(layer "F.Fab")
		)
		(fp_line
			(start -0.12065 -0.2794)
			(end 0.12065 -0.2794)
			(stroke
				(width 0.1)
				(type default)
			)
			(layer "F.Fab")
		)
		(fp_line
			(start 0.120396 0.2794)
			(end -0.12065 0.2794)
			(stroke
				(width 0.1)
				(type default)
			)
			(layer "F.Fab")
		)
		(fp_line
			(start -0.12065 0.2794)
			(end -0.12065 0.3048)
			(stroke
				(width 0.1)
				(type default)
			)
			(layer "F.Fab")
		)
		(fp_line
			(start 0.67945 0.3048)
			(end 0.120396 0.3048)
			(stroke
				(width 0.1)
				(type default)
			)
			(layer "F.Fab")
		)
		(fp_line
			(start 0.120396 0.3048)
			(end 0.120396 0.2794)
			(stroke
				(width 0.1)
				(type default)
			)
			(layer "F.Fab")
		)
		(fp_line
			(start -0.12065 0.3048)
			(end -0.67945 0.3048)
			(stroke
				(width 0.1)
				(type default)
			)
			(layer "F.Fab")
		)
		(fp_line
			(start -0.67945 0.3048)
			(end -0.67945 -0.305054)
			(stroke
				(width 0.1)
				(type default)
			)
			(layer "F.Fab")
		)
		(pad "1" smd circle
			(at -0.40005 0 90)
			(size 0 0)
			(layers "F.Cu" "F.Mask" "F.Paste")
			(net "PVDD11_S3_P1_VCCS")
		)
		(pad "2" smd circle
			(at 0.40005 0 90)
			(size 0 0)
			(layers "F.Cu" "F.Mask" "F.Paste")
			(net "GND")
		)
	)
	(footprint ""
		(layer "F.Cu")
		(at 275.14169 -97.339404 180)
		(property "Reference" "R1643"
			(at 0 0 180)
			(layer "F.SilkS")
			(hide yes)
			(effects
				(font
					(size 1.27 1.27)
				)
			)
		)
		(property "Value" ""
			(at 0 0 180)
			(layer "F.Fab")
			(effects
				(font
					(size 1.27 1.27)
				)
			)
		)
		(duplicate_pad_numbers_are_jumpers no)
		(fp_line
			(start 0.7874 0.4064)
			(end -0.7874 0.4064)
			(stroke
				(width 0.1524)
				(type default)
			)
			(layer "F.SilkS")
		)
		(fp_line
			(start 0.7874 -0.4064)
			(end 0.7874 0.4064)
			(stroke
				(width 0.1524)
				(type default)
			)
			(layer "F.SilkS")
		)
		(fp_line
			(start -0.7874 0.4064)
			(end -0.7874 -0.4064)
			(stroke
				(width 0.1524)
				(type default)
			)
			(layer "F.SilkS")
		)
		(fp_line
			(start -0.7874 -0.4064)
			(end 0.7874 -0.4064)
			(stroke
				(width 0.1524)
				(type default)
			)
			(layer "F.SilkS")
		)
		(fp_line
			(start 0.67945 0.3048)
			(end 0.120396 0.3048)
			(stroke
				(width 0.1)
				(type default)
			)
			(layer "F.Fab")
		)
		(fp_line
			(start 0.67945 -0.3048)
			(end 0.67945 0.3048)
			(stroke
				(width 0.1)
				(type default)
			)
			(layer "F.Fab")
		)
		(fp_line
			(start 0.12065 -0.2794)
			(end 0.12065 -0.3048)
			(stroke
				(width 0.1)
				(type default)
			)
			(layer "F.Fab")
		)
		(fp_line
			(start 0.12065 -0.3048)
			(end 0.67945 -0.3048)
			(stroke
				(width 0.1)
				(type default)
			)
			(layer "F.Fab")
		)
		(fp_line
			(start 0.120396 0.3048)
			(end 0.120396 0.2794)
			(stroke
				(width 0.1)
				(type default)
			)
			(layer "F.Fab")
		)
		(fp_line
			(start 0.120396 0.2794)
			(end -0.12065 0.2794)
			(stroke
				(width 0.1)
				(type default)
			)
			(layer "F.Fab")
		)
		(fp_line
			(start -0.12065 0.3048)
			(end -0.67945 0.3048)
			(stroke
				(width 0.1)
				(type default)
			)
			(layer "F.Fab")
		)
		(fp_line
			(start -0.12065 0.2794)
			(end -0.12065 0.3048)
			(stroke
				(width 0.1)
				(type default)
			)
			(layer "F.Fab")
		)
		(fp_line
			(start -0.12065 -0.2794)
			(end 0.12065 -0.2794)
			(stroke
				(width 0.1)
				(type default)
			)
			(layer "F.Fab")
		)
		(fp_line
			(start -0.12065 -0.305054)
			(end -0.12065 -0.2794)
			(stroke
				(width 0.1)
				(type default)
			)
			(layer "F.Fab")
		)
		(fp_line
			(start -0.67945 0.3048)
			(end -0.67945 -0.305054)
			(stroke
				(width 0.1)
				(type default)
			)
			(layer "F.Fab")
		)
		(fp_line
			(start -0.67945 -0.305054)
			(end -0.12065 -0.305054)
			(stroke
				(width 0.1)
				(type default)
			)
			(layer "F.Fab")
		)
		(pad "1" smd circle
			(at -0.40005 0 180)
			(size 0 0)
			(layers "F.Cu" "F.Mask" "F.Paste")
			(net "JTAG_P1_R_TMS")
		)
		(pad "2" smd circle
			(at 0.40005 0 180)
			(size 0 0)
			(layers "F.Cu" "F.Mask" "F.Paste")
			(net "JTAG_CPU1_TMS")
		)
	)
	(footprint ""
		(layer "F.Cu")
		(at 366.64392 -396.412974 90)
		(property "Reference" "R636"
			(at 0 0 90)
			(layer "F.SilkS")
			(hide yes)
			(effects
				(font
					(size 1.27 1.27)
				)
			)
		)
		(property "Value" ""
			(at 0 0 90)
			(layer "F.Fab")
			(effects
				(font
					(size 1.27 1.27)
				)
			)
		)
		(duplicate_pad_numbers_are_jumpers no)
		(fp_line
			(start 0.32512 -0.175006)
			(end 0.32512 0.175006)
			(stroke
				(width 0.1)
				(type default)
			)
			(layer "F.Fab")
		)
		(fp_line
			(start -0.32512 -0.175006)
			(end 0.32512 -0.175006)
			(stroke
				(width 0.1)
				(type default)
			)
			(layer "F.Fab")
		)
		(fp_line
			(start 0.32512 0.175006)
			(end -0.32512 0.175006)
			(stroke
				(width 0.1)
				(type default)
			)
			(layer "F.Fab")
		)
		(fp_line
			(start -0.32512 0.175006)
			(end -0.32512 -0.175006)
			(stroke
				(width 0.1)
				(type default)
			)
			(layer "F.Fab")
		)
		(pad "1" smd rect
			(at -0.2667 0 90)
			(size 0.3048 0.381)
			(layers "F.Cu" "F.Mask" "F.Paste")
			(net "CLK_100M_RETIMER_CPU0_P3_DP")
		)
		(pad "2" smd rect
			(at 0.2667 0 270)
			(size 0.3048 0.381)
			(layers "F.Cu" "F.Mask" "F.Paste")
			(net "GND")
		)
	)
	(footprint ""
		(layer "F.Cu")
		(at 398.276318 -76.661264)
		(property "Reference" "C1108"
			(at 0 0 0)
			(layer "F.SilkS")
			(hide yes)
			(effects
				(font
					(size 1.27 1.27)
				)
			)
		)
		(property "Value" ""
			(at 0 0 0)
			(layer "F.Fab")
			(effects
				(font
					(size 1.27 1.27)
				)
			)
		)
		(duplicate_pad_numbers_are_jumpers no)
		(fp_line
			(start -0.7874 -0.4064)
			(end 0.7874 -0.4064)
			(stroke
				(width 0.1524)
				(type default)
			)
			(layer "F.SilkS")
		)
		(fp_line
			(start -0.7874 0.4064)
			(end -0.7874 -0.4064)
			(stroke
				(width 0.1524)
				(type default)
			)
			(layer "F.SilkS")
		)
		(fp_line
			(start 0.7874 -0.4064)
			(end 0.7874 0.4064)
			(stroke
				(width 0.1524)
				(type default)
			)
			(layer "F.SilkS")
		)
		(fp_line
			(start 0.7874 0.4064)
			(end -0.7874 0.4064)
			(stroke
				(width 0.1524)
				(type default)
			)
			(layer "F.SilkS")
		)
		(fp_line
			(start -0.67945 -0.305054)
			(end -0.12065 -0.305054)
			(stroke
				(width 0.1)
				(type default)
			)
			(layer "F.Fab")
		)
		(fp_line
			(start -0.67945 0.3048)
			(end -0.67945 -0.305054)
			(stroke
				(width 0.1)
				(type default)
			)
			(layer "F.Fab")
		)
		(fp_line
			(start -0.12065 -0.305054)
			(end -0.12065 -0.2794)
			(stroke
				(width 0.1)
				(type default)
			)
			(layer "F.Fab")
		)
		(fp_line
			(start -0.12065 -0.2794)
			(end 0.12065 -0.2794)
			(stroke
				(width 0.1)
				(type default)
			)
			(layer "F.Fab")
		)
		(fp_line
			(start -0.12065 0.2794)
			(end -0.12065 0.3048)
			(stroke
				(width 0.1)
				(type default)
			)
			(layer "F.Fab")
		)
		(fp_line
			(start -0.12065 0.3048)
			(end -0.67945 0.3048)
			(stroke
				(width 0.1)
				(type default)
			)
			(layer "F.Fab")
		)
		(fp_line
			(start 0.120396 0.2794)
			(end -0.12065 0.2794)
			(stroke
				(width 0.1)
				(type default)
			)
			(layer "F.Fab")
		)
		(fp_line
			(start 0.120396 0.3048)
			(end 0.120396 0.2794)
			(stroke
				(width 0.1)
				(type default)
			)
			(layer "F.Fab")
		)
		(fp_line
			(start 0.12065 -0.3048)
			(end 0.67945 -0.3048)
			(stroke
				(width 0.1)
				(type default)
			)
			(layer "F.Fab")
		)
		(fp_line
			(start 0.12065 -0.2794)
			(end 0.12065 -0.3048)
			(stroke
				(width 0.1)
				(type default)
			)
			(layer "F.Fab")
		)
		(fp_line
			(start 0.67945 -0.3048)
			(end 0.67945 0.3048)
			(stroke
				(width 0.1)
				(type default)
			)
			(layer "F.Fab")
		)
		(fp_line
			(start 0.67945 0.3048)
			(end 0.120396 0.3048)
			(stroke
				(width 0.1)
				(type default)
			)
			(layer "F.Fab")
		)
		(pad "1" smd circle
			(at -0.40005 0)
			(size 0 0)
			(layers "F.Cu" "F.Mask" "F.Paste")
			(net "P12V_OCP_SFF")
		)
		(pad "2" smd circle
			(at 0.40005 0)
			(size 0 0)
			(layers "F.Cu" "F.Mask" "F.Paste")
			(net "GND")
		)
	)
	(footprint ""
		(layer "F.Cu")
		(at 351.407222 -425.295314)
		(property "Reference" "R4562"
			(at 0 0 0)
			(layer "F.SilkS")
			(hide yes)
			(effects
				(font
					(size 1.27 1.27)
				)
			)
		)
		(property "Value" ""
			(at 0 0 0)
			(layer "F.Fab")
			(effects
				(font
					(size 1.27 1.27)
				)
			)
		)
		(duplicate_pad_numbers_are_jumpers no)
		(fp_line
			(start -0.7874 -0.4064)
			(end 0.7874 -0.4064)
			(stroke
				(width 0.1524)
				(type default)
			)
			(layer "F.SilkS")
		)
		(fp_line
			(start -0.7874 0.4064)
			(end -0.7874 -0.4064)
			(stroke
				(width 0.1524)
				(type default)
			)
			(layer "F.SilkS")
		)
		(fp_line
			(start 0.7874 -0.4064)
			(end 0.7874 0.4064)
			(stroke
				(width 0.1524)
				(type default)
			)
			(layer "F.SilkS")
		)
		(fp_line
			(start 0.7874 0.4064)
			(end -0.7874 0.4064)
			(stroke
				(width 0.1524)
				(type default)
			)
			(layer "F.SilkS")
		)
		(fp_line
			(start -0.67945 -0.305054)
			(end -0.12065 -0.305054)
			(stroke
				(width 0.1)
				(type default)
			)
			(layer "F.Fab")
		)
		(fp_line
			(start -0.67945 0.3048)
			(end -0.67945 -0.305054)
			(stroke
				(width 0.1)
				(type default)
			)
			(layer "F.Fab")
		)
		(fp_line
			(start -0.12065 -0.305054)
			(end -0.12065 -0.2794)
			(stroke
				(width 0.1)
				(type default)
			)
			(layer "F.Fab")
		)
		(fp_line
			(start -0.12065 -0.2794)
			(end 0.12065 -0.2794)
			(stroke
				(width 0.1)
				(type default)
			)
			(layer "F.Fab")
		)
		(fp_line
			(start -0.12065 0.2794)
			(end -0.12065 0.3048)
			(stroke
				(width 0.1)
				(type default)
			)
			(layer "F.Fab")
		)
		(fp_line
			(start -0.12065 0.3048)
			(end -0.67945 0.3048)
			(stroke
				(width 0.1)
				(type default)
			)
			(layer "F.Fab")
		)
		(fp_line
			(start 0.120396 0.2794)
			(end -0.12065 0.2794)
			(stroke
				(width 0.1)
				(type default)
			)
			(layer "F.Fab")
		)
		(fp_line
			(start 0.120396 0.3048)
			(end 0.120396 0.2794)
			(stroke
				(width 0.1)
				(type default)
			)
			(layer "F.Fab")
		)
		(fp_line
			(start 0.12065 -0.3048)
			(end 0.67945 -0.3048)
			(stroke
				(width 0.1)
				(type default)
			)
			(layer "F.Fab")
		)
		(fp_line
			(start 0.12065 -0.2794)
			(end 0.12065 -0.3048)
			(stroke
				(width 0.1)
				(type default)
			)
			(layer "F.Fab")
		)
		(fp_line
			(start 0.67945 -0.3048)
			(end 0.67945 0.3048)
			(stroke
				(width 0.1)
				(type default)
			)
			(layer "F.Fab")
		)
		(fp_line
			(start 0.67945 0.3048)
			(end 0.120396 0.3048)
			(stroke
				(width 0.1)
				(type default)
			)
			(layer "F.Fab")
		)
		(pad "1" smd circle
			(at -0.40005 0)
			(size 0 0)
			(layers "F.Cu" "F.Mask" "F.Paste")
			(net "P3V3_AUX")
		)
		(pad "2" smd circle
			(at 0.40005 0)
			(size 0 0)
			(layers "F.Cu" "F.Mask" "F.Paste")
			(net "SWB_HSC_PWRGD")
		)
	)
)
